(kicad_pcb
	(version 20260206)
	(generator "pcbnew")
	(generator_version "10.0")
	(general
		(thickness 1.6)
		(legacy_teardrops no)
	)
	(paper "A4")
	(title_block
		(title "01162023_DA0F0TEBIF0_F0T_Expander_BD_F_brd_V02_OCP.brd")
		(comment 1 "Grand Teton / footprints 9064-9071 of 9728")
	)
	(layers
		(0 "F.Cu" signal "TOP")
		(4 "In1.Cu" signal "GND")
		(6 "In2.Cu" signal "VCC")
		(8 "In3.Cu" signal "VCC1")
		(10 "In4.Cu" signal "GND1")
		(12 "In5.Cu" signal "IN1")
		(14 "In6.Cu" signal "GND2")
		(16 "In7.Cu" signal "IN2")
		(18 "In8.Cu" signal "GND3")
		(20 "In9.Cu" signal "IN3")
		(22 "In10.Cu" signal "GND4")
		(24 "In11.Cu" signal "IN4")
		(26 "In12.Cu" signal "GND5")
		(28 "In13.Cu" signal "IN5")
		(30 "In14.Cu" signal "GND6")
		(32 "In15.Cu" signal "IN6")
		(34 "In16.Cu" signal "GND7")
		(2 "B.Cu" signal "BOTTOM")
		(9 "F.Adhes" user "F.Adhesive")
		(11 "B.Adhes" user "B.Adhesive")
		(13 "F.Paste" user "Package Geometry/Pastemask Top")
		(15 "B.Paste" user "Package Geometry/Pastemask Bottom")
		(5 "F.SilkS" user "Ref Des/Silkscreen Top")
		(7 "B.SilkS" user "Ref Des/Silkscreen Bottom")
		(1 "F.Mask" user "Board Geometry/Soldermask Top")
		(3 "B.Mask" user "Board Geometry/Soldermask Bottom")
		(17 "Dwgs.User" user "User.Drawings")
		(19 "Cmts.User" user "User.Comments")
		(21 "Eco1.User" user "User.Eco1")
		(23 "Eco2.User" user "User.Eco2")
		(25 "Edge.Cuts" user "Board Geometry/Outline")
		(27 "Margin" user)
		(31 "F.CrtYd" user "Package Geometry/Place Bound Top")
		(29 "B.CrtYd" user "Package Geometry/Place Bound Bottom")
		(35 "F.Fab" user "Ref Des/Assembly Top")
		(33 "B.Fab" user "Ref Des/Assembly Bottom")
	)
	(footprint ""
		(layer "B.Cu")
		(at 354.889562 -313.620404)
		(property "Reference" "R5797"
			(at 0 0 0)
			(layer "B.SilkS")
			(hide yes)
			(effects
				(font
					(size 1.27 1.27)
				)
				(justify mirror)
			)
		)
		(property "Value" ""
			(at 0 0 0)
			(layer "B.Fab")
			(effects
				(font
					(size 1.27 1.27)
				)
				(justify mirror)
			)
		)
		(duplicate_pad_numbers_are_jumpers no)
		(fp_line
			(start -2.576322 -1.1303)
			(end -2.576322 1.1303)
			(stroke
				(width 0.1524)
				(type default)
			)
			(layer "B.SilkS")
		)
		(fp_line
			(start -2.576322 1.1303)
			(end 2.576322 1.1303)
			(stroke
				(width 0.1524)
				(type default)
			)
			(layer "B.SilkS")
		)
		(fp_line
			(start 2.576322 -1.1303)
			(end -2.576322 -1.1303)
			(stroke
				(width 0.1524)
				(type default)
			)
			(layer "B.SilkS")
		)
		(fp_line
			(start 2.576322 1.1303)
			(end 2.576322 -1.1303)
			(stroke
				(width 0.1524)
				(type default)
			)
			(layer "B.SilkS")
		)
		(fp_line
			(start -1.649984 -0.899922)
			(end 1.649984 -0.899922)
			(stroke
				(width 0.1)
				(type default)
			)
			(layer "B.Fab")
		)
		(fp_line
			(start -1.649984 0.899922)
			(end -1.649984 -0.899922)
			(stroke
				(width 0.1)
				(type default)
			)
			(layer "B.Fab")
		)
		(fp_line
			(start 1.649984 -0.899922)
			(end 1.649984 0.899922)
			(stroke
				(width 0.1)
				(type default)
			)
			(layer "B.Fab")
		)
		(fp_line
			(start 1.649984 0.899922)
			(end -1.649984 0.899922)
			(stroke
				(width 0.1)
				(type default)
			)
			(layer "B.Fab")
		)
		(pad "1A" smd rect
			(at 1.700022 0 180)
			(size 1.4986 2.0066)
			(layers "B.Cu" "B.Mask" "B.Paste")
			(net "P0V8_PEX3")
		)
		(pad "1B" smd rect
			(at 1.077722 0 180)
			(size 0.254 0.508)
			(layers "B.Cu" "B.Mask" "B.Paste")
			(net "P0V8_PEX3")
		)
		(pad "2A" smd rect
			(at -1.700022 0 180)
			(size 1.4986 2.0066)
			(layers "B.Cu" "B.Mask" "B.Paste")
			(net "P0V8_SERDES_VDDA_PEX3")
		)
		(pad "2B" smd rect
			(at -1.077722 0 180)
			(size 0.254 0.508)
			(layers "B.Cu" "B.Mask" "B.Paste")
			(net "P0V8_SERDES_VDDA_PEX3")
		)
	)
	(footprint ""
		(layer "B.Cu")
		(at 295.649904 -299.699934 -90)
		(property "Reference" "C1724"
			(at 0 0 90)
			(layer "B.SilkS")
			(hide yes)
			(effects
				(font
					(size 1.27 1.27)
				)
				(justify mirror)
			)
		)
		(property "Value" ""
			(at 0 0 90)
			(layer "B.Fab")
			(effects
				(font
					(size 1.27 1.27)
				)
				(justify mirror)
			)
		)
		(duplicate_pad_numbers_are_jumpers no)
		(fp_line
			(start -0.299974 0.150114)
			(end 0.299974 0.150114)
			(stroke
				(width 0.1)
				(type default)
			)
			(layer "B.Fab")
		)
		(fp_line
			(start 0.299974 0.150114)
			(end 0.299974 -0.150114)
			(stroke
				(width 0.1)
				(type default)
			)
			(layer "B.Fab")
		)
		(fp_line
			(start -0.299974 -0.150114)
			(end -0.299974 0.150114)
			(stroke
				(width 0.1)
				(type default)
			)
			(layer "B.Fab")
		)
		(fp_line
			(start 0.299974 -0.150114)
			(end -0.299974 -0.150114)
			(stroke
				(width 0.1)
				(type default)
			)
			(layer "B.Fab")
		)
		(pad "1" smd rect
			(at 0.2667 0 90)
			(size 0.3048 0.381)
			(layers "B.Cu" "B.Mask" "B.Paste")
			(net "P0V8_SERDES_VDDA_PEX2")
		)
		(pad "2" smd rect
			(at -0.2667 0 90)
			(size 0.3048 0.381)
			(layers "B.Cu" "B.Mask" "B.Paste")
			(net "GND")
		)
	)
	(footprint ""
		(layer "B.Cu")
		(at 234.89412 -94.421706)
		(property "Reference" "R1006"
			(at 0 0 0)
			(layer "B.SilkS")
			(hide yes)
			(effects
				(font
					(size 1.27 1.27)
				)
				(justify mirror)
			)
		)
		(property "Value" ""
			(at 0 0 0)
			(layer "B.Fab")
			(effects
				(font
					(size 1.27 1.27)
				)
				(justify mirror)
			)
		)
		(duplicate_pad_numbers_are_jumpers no)
		(fp_line
			(start -0.7874 -0.4064)
			(end -0.7874 0.4064)
			(stroke
				(width 0.1524)
				(type default)
			)
			(layer "B.SilkS")
		)
		(fp_line
			(start -0.7874 0.4064)
			(end 0.7874 0.4064)
			(stroke
				(width 0.1524)
				(type default)
			)
			(layer "B.SilkS")
		)
		(fp_line
			(start 0.7874 -0.4064)
			(end -0.7874 -0.4064)
			(stroke
				(width 0.1524)
				(type default)
			)
			(layer "B.SilkS")
		)
		(fp_line
			(start 0.7874 0.4064)
			(end 0.7874 -0.4064)
			(stroke
				(width 0.1524)
				(type default)
			)
			(layer "B.SilkS")
		)
		(fp_line
			(start -0.67945 -0.3048)
			(end -0.67945 0.3048)
			(stroke
				(width 0.1)
				(type default)
			)
			(layer "B.Fab")
		)
		(fp_line
			(start -0.67945 0.3048)
			(end -0.120396 0.3048)
			(stroke
				(width 0.1)
				(type default)
			)
			(layer "B.Fab")
		)
		(fp_line
			(start -0.12065 -0.3048)
			(end -0.67945 -0.3048)
			(stroke
				(width 0.1)
				(type default)
			)
			(layer "B.Fab")
		)
		(fp_line
			(start -0.12065 -0.2794)
			(end -0.12065 -0.3048)
			(stroke
				(width 0.1)
				(type default)
			)
			(layer "B.Fab")
		)
		(fp_line
			(start -0.120396 0.2794)
			(end 0.12065 0.2794)
			(stroke
				(width 0.1)
				(type default)
			)
			(layer "B.Fab")
		)
		(fp_line
			(start -0.120396 0.3048)
			(end -0.120396 0.2794)
			(stroke
				(width 0.1)
				(type default)
			)
			(layer "B.Fab")
		)
		(fp_line
			(start 0.12065 -0.305054)
			(end 0.12065 -0.2794)
			(stroke
				(width 0.1)
				(type default)
			)
			(layer "B.Fab")
		)
		(fp_line
			(start 0.12065 -0.2794)
			(end -0.12065 -0.2794)
			(stroke
				(width 0.1)
				(type default)
			)
			(layer "B.Fab")
		)
		(fp_line
			(start 0.12065 0.2794)
			(end 0.12065 0.3048)
			(stroke
				(width 0.1)
				(type default)
			)
			(layer "B.Fab")
		)
		(fp_line
			(start 0.12065 0.3048)
			(end 0.67945 0.3048)
			(stroke
				(width 0.1)
				(type default)
			)
			(layer "B.Fab")
		)
		(fp_line
			(start 0.67945 -0.305054)
			(end 0.12065 -0.305054)
			(stroke
				(width 0.1)
				(type default)
			)
			(layer "B.Fab")
		)
		(fp_line
			(start 0.67945 0.3048)
			(end 0.67945 -0.305054)
			(stroke
				(width 0.1)
				(type default)
			)
			(layer "B.Fab")
		)
		(pad "1" smd circle
			(at 0.40005 0 180)
			(size 0 0)
			(layers "B.Cu" "B.Mask" "B.Paste")
			(net "P3V3_AUX")
		)
		(pad "2" smd circle
			(at -0.40005 0 180)
			(size 0 0)
			(layers "B.Cu" "B.Mask" "B.Paste")
			(net "P3V3_PEX_USB_HUB")
		)
	)
	(footprint ""
		(layer "B.Cu")
		(at 178.124866 -305.399948 -90)
		(property "Reference" "C3140"
			(at 0 0 90)
			(layer "B.SilkS")
			(hide yes)
			(effects
				(font
					(size 1.27 1.27)
				)
				(justify mirror)
			)
		)
		(property "Value" ""
			(at 0 0 90)
			(layer "B.Fab")
			(effects
				(font
					(size 1.27 1.27)
				)
				(justify mirror)
			)
		)
		(duplicate_pad_numbers_are_jumpers no)
		(fp_line
			(start -0.299974 0.150114)
			(end 0.299974 0.150114)
			(stroke
				(width 0.1)
				(type default)
			)
			(layer "B.Fab")
		)
		(fp_line
			(start 0.299974 0.150114)
			(end 0.299974 -0.150114)
			(stroke
				(width 0.1)
				(type default)
			)
			(layer "B.Fab")
		)
		(fp_line
			(start -0.299974 -0.150114)
			(end -0.299974 0.150114)
			(stroke
				(width 0.1)
				(type default)
			)
			(layer "B.Fab")
		)
		(fp_line
			(start 0.299974 -0.150114)
			(end -0.299974 -0.150114)
			(stroke
				(width 0.1)
				(type default)
			)
			(layer "B.Fab")
		)
		(pad "1" smd rect
			(at 0.2667 0 90)
			(size 0.3048 0.381)
			(layers "B.Cu" "B.Mask" "B.Paste")
			(net "P1V25_SERDES_VDDPLL_PEX1")
		)
		(pad "2" smd rect
			(at -0.2667 0 90)
			(size 0.3048 0.381)
			(layers "B.Cu" "B.Mask" "B.Paste")
			(net "GND")
		)
	)
	(footprint ""
		(layer "B.Cu")
		(at 272.318988 -294.8051 180)
		(property "Reference" "R3473"
			(at 0 0 0)
			(layer "B.SilkS")
			(hide yes)
			(effects
				(font
					(size 1.27 1.27)
				)
				(justify mirror)
			)
		)
		(property "Value" ""
			(at 0 0 0)
			(layer "B.Fab")
			(effects
				(font
					(size 1.27 1.27)
				)
				(justify mirror)
			)
		)
		(duplicate_pad_numbers_are_jumpers no)
		(fp_line
			(start 0.7874 0.4064)
			(end 0.7874 -0.4064)
			(stroke
				(width 0.1524)
				(type default)
			)
			(layer "B.SilkS")
		)
		(fp_line
			(start 0.7874 -0.4064)
			(end -0.7874 -0.4064)
			(stroke
				(width 0.1524)
				(type default)
			)
			(layer "B.SilkS")
		)
		(fp_line
			(start -0.7874 0.4064)
			(end 0.7874 0.4064)
			(stroke
				(width 0.1524)
				(type default)
			)
			(layer "B.SilkS")
		)
		(fp_line
			(start -0.7874 -0.4064)
			(end -0.7874 0.4064)
			(stroke
				(width 0.1524)
				(type default)
			)
			(layer "B.SilkS")
		)
		(fp_line
			(start 0.67945 0.3048)
			(end 0.67945 -0.305054)
			(stroke
				(width 0.1)
				(type default)
			)
			(layer "B.Fab")
		)
		(fp_line
			(start 0.67945 -0.305054)
			(end 0.12065 -0.305054)
			(stroke
				(width 0.1)
				(type default)
			)
			(layer "B.Fab")
		)
		(fp_line
			(start 0.12065 0.3048)
			(end 0.67945 0.3048)
			(stroke
				(width 0.1)
				(type default)
			)
			(layer "B.Fab")
		)
		(fp_line
			(start 0.12065 0.2794)
			(end 0.12065 0.3048)
			(stroke
				(width 0.1)
				(type default)
			)
			(layer "B.Fab")
		)
		(fp_line
			(start 0.12065 -0.2794)
			(end -0.12065 -0.2794)
			(stroke
				(width 0.1)
				(type default)
			)
			(layer "B.Fab")
		)
		(fp_line
			(start 0.12065 -0.305054)
			(end 0.12065 -0.2794)
			(stroke
				(width 0.1)
				(type default)
			)
			(layer "B.Fab")
		)
		(fp_line
			(start -0.120396 0.3048)
			(end -0.120396 0.2794)
			(stroke
				(width 0.1)
				(type default)
			)
			(layer "B.Fab")
		)
		(fp_line
			(start -0.120396 0.2794)
			(end 0.12065 0.2794)
			(stroke
				(width 0.1)
				(type default)
			)
			(layer "B.Fab")
		)
		(fp_line
			(start -0.12065 -0.2794)
			(end -0.12065 -0.3048)
			(stroke
				(width 0.1)
				(type default)
			)
			(layer "B.Fab")
		)
		(fp_line
			(start -0.12065 -0.3048)
			(end -0.67945 -0.3048)
			(stroke
				(width 0.1)
				(type default)
			)
			(layer "B.Fab")
		)
		(fp_line
			(start -0.67945 0.3048)
			(end -0.120396 0.3048)
			(stroke
				(width 0.1)
				(type default)
			)
			(layer "B.Fab")
		)
		(fp_line
			(start -0.67945 -0.3048)
			(end -0.67945 0.3048)
			(stroke
				(width 0.1)
				(type default)
			)
			(layer "B.Fab")
		)
		(pad "1" smd circle
			(at 0.40005 0)
			(size 0 0)
			(layers "B.Cu" "B.Mask" "B.Paste")
			(net "SPI_PEX2_SDIO2_R")
		)
		(pad "2" smd circle
			(at -0.40005 0)
			(size 0 0)
			(layers "B.Cu" "B.Mask" "B.Paste")
			(net "SPI_PEX2_SDIO2")
		)
	)
	(footprint ""
		(layer "B.Cu")
		(at 120.03786 -325.186294 -90)
		(property "Reference" "C4269"
			(at 0 0 90)
			(layer "B.SilkS")
			(hide yes)
			(effects
				(font
					(size 1.27 1.27)
				)
				(justify mirror)
			)
		)
		(property "Value" ""
			(at 0 0 90)
			(layer "B.Fab")
			(effects
				(font
					(size 1.27 1.27)
				)
				(justify mirror)
			)
		)
		(duplicate_pad_numbers_are_jumpers no)
		(fp_line
			(start -1.2954 0.5842)
			(end 1.2954 0.5842)
			(stroke
				(width 0.1524)
				(type default)
			)
			(layer "B.SilkS")
		)
		(fp_line
			(start 1.2954 0.5842)
			(end 1.2954 -0.5842)
			(stroke
				(width 0.1524)
				(type default)
			)
			(layer "B.SilkS")
		)
		(fp_line
			(start -1.2954 -0.5842)
			(end -1.2954 0.5842)
			(stroke
				(width 0.1524)
				(type default)
			)
			(layer "B.SilkS")
		)
		(fp_line
			(start 1.2954 -0.5842)
			(end -1.2954 -0.5842)
			(stroke
				(width 0.1524)
				(type default)
			)
			(layer "B.SilkS")
		)
		(fp_line
			(start -0.8636 0.4572)
			(end 0.8636 0.4572)
			(stroke
				(width 0.1)
				(type default)
			)
			(layer "B.Fab")
		)
		(fp_line
			(start 0.8636 0.4572)
			(end 0.8636 0.4064)
			(stroke
				(width 0.1)
				(type default)
			)
			(layer "B.Fab")
		)
		(fp_line
			(start -1.1938 0.4064)
			(end -0.8636 0.4064)
			(stroke
				(width 0.1)
				(type default)
			)
			(layer "B.Fab")
		)
		(fp_line
			(start -0.8636 0.4064)
			(end -0.8636 0.4572)
			(stroke
				(width 0.1)
				(type default)
			)
			(layer "B.Fab")
		)
		(fp_line
			(start 0.8636 0.4064)
			(end 1.1938 0.4064)
			(stroke
				(width 0.1)
				(type default)
			)
			(layer "B.Fab")
		)
		(fp_line
			(start 1.1938 0.4064)
			(end 1.1938 -0.4064)
			(stroke
				(width 0.1)
				(type default)
			)
			(layer "B.Fab")
		)
		(fp_line
			(start -1.1938 -0.4064)
			(end -1.1938 0.4064)
			(stroke
				(width 0.1)
				(type default)
			)
			(layer "B.Fab")
		)
		(fp_line
			(start -0.8636 -0.4064)
			(end -1.1938 -0.4064)
			(stroke
				(width 0.1)
				(type default)
			)
			(layer "B.Fab")
		)
		(fp_line
			(start 0.8636 -0.4064)
			(end 0.8636 -0.4572)
			(stroke
				(width 0.1)
				(type default)
			)
			(layer "B.Fab")
		)
		(fp_line
			(start 1.1938 -0.4064)
			(end 0.8636 -0.4064)
			(stroke
				(width 0.1)
				(type default)
			)
			(layer "B.Fab")
		)
		(fp_line
			(start -0.8636 -0.4572)
			(end -0.8636 -0.4064)
			(stroke
				(width 0.1)
				(type default)
			)
			(layer "B.Fab")
		)
		(fp_line
			(start 0.8636 -0.4572)
			(end -0.8636 -0.4572)
			(stroke
				(width 0.1)
				(type default)
			)
			(layer "B.Fab")
		)
		(pad "1" smd rect
			(at 0.7366 0 180)
			(size 0.7112 0.8128)
			(layers "B.Cu" "B.Mask" "B.Paste")
			(net "P0V8_SERDES_VDDA_PEX1_C7")
		)
		(pad "2" smd rect
			(at -0.7366 0 180)
			(size 0.7112 0.8128)
			(layers "B.Cu" "B.Mask" "B.Paste")
			(net "GND")
		)
	)
	(footprint ""
		(layer "B.Cu")
		(at 283.774896 -286.399732 90)
		(property "Reference" "C3320"
			(at 0 0 90)
			(layer "B.SilkS")
			(hide yes)
			(effects
				(font
					(size 1.27 1.27)
				)
				(justify mirror)
			)
		)
		(property "Value" ""
			(at 0 0 90)
			(layer "B.Fab")
			(effects
				(font
					(size 1.27 1.27)
				)
				(justify mirror)
			)
		)
		(duplicate_pad_numbers_are_jumpers no)
		(fp_line
			(start 0.299974 -0.150114)
			(end -0.299974 -0.150114)
			(stroke
				(width 0.1)
				(type default)
			)
			(layer "B.Fab")
		)
		(fp_line
			(start -0.299974 -0.150114)
			(end -0.299974 0.150114)
			(stroke
				(width 0.1)
				(type default)
			)
			(layer "B.Fab")
		)
		(fp_line
			(start 0.299974 0.150114)
			(end 0.299974 -0.150114)
			(stroke
				(width 0.1)
				(type default)
			)
			(layer "B.Fab")
		)
		(fp_line
			(start -0.299974 0.150114)
			(end 0.299974 0.150114)
			(stroke
				(width 0.1)
				(type default)
			)
			(layer "B.Fab")
		)
		(pad "1" smd rect
			(at 0.2667 0 270)
			(size 0.3048 0.381)
			(layers "B.Cu" "B.Mask" "B.Paste")
			(net "P1V25_SERDES_VDDPLL_PEX2")
		)
		(pad "2" smd rect
			(at -0.2667 0 270)
			(size 0.3048 0.381)
			(layers "B.Cu" "B.Mask" "B.Paste")
			(net "GND")
		)
	)
	(footprint ""
		(layer "B.Cu")
		(at 376.178064 -243.589302)
		(property "Reference" "C2605"
			(at 0 0 0)
			(layer "B.SilkS")
			(hide yes)
			(effects
				(font
					(size 1.27 1.27)
				)
				(justify mirror)
			)
		)
		(property "Value" ""
			(at 0 0 0)
			(layer "B.Fab")
			(effects
				(font
					(size 1.27 1.27)
				)
				(justify mirror)
			)
		)
		(duplicate_pad_numbers_are_jumpers no)
		(fp_line
			(start -0.7874 -0.4064)
			(end -0.7874 0.4064)
			(stroke
				(width 0.1524)
				(type default)
			)
			(layer "B.SilkS")
		)
		(fp_line
			(start -0.7874 0.4064)
			(end 0.7874 0.4064)
			(stroke
				(width 0.1524)
				(type default)
			)
			(layer "B.SilkS")
		)
		(fp_line
			(start 0.7874 -0.4064)
			(end -0.7874 -0.4064)
			(stroke
				(width 0.1524)
				(type default)
			)
			(layer "B.SilkS")
		)
		(fp_line
			(start 0.7874 0.4064)
			(end 0.7874 -0.4064)
			(stroke
				(width 0.1524)
				(type default)
			)
			(layer "B.SilkS")
		)
		(fp_line
			(start -0.67945 -0.3048)
			(end -0.67945 0.3048)
			(stroke
				(width 0.1)
				(type default)
			)
			(layer "B.Fab")
		)
		(fp_line
			(start -0.67945 0.3048)
			(end -0.120396 0.3048)
			(stroke
				(width 0.1)
				(type default)
			)
			(layer "B.Fab")
		)
		(fp_line
			(start -0.12065 -0.3048)
			(end -0.67945 -0.3048)
			(stroke
				(width 0.1)
				(type default)
			)
			(layer "B.Fab")
		)
		(fp_line
			(start -0.12065 -0.2794)
			(end -0.12065 -0.3048)
			(stroke
				(width 0.1)
				(type default)
			)
			(layer "B.Fab")
		)
		(fp_line
			(start -0.120396 0.2794)
			(end 0.12065 0.2794)
			(stroke
				(width 0.1)
				(type default)
			)
			(layer "B.Fab")
		)
		(fp_line
			(start -0.120396 0.3048)
			(end -0.120396 0.2794)
			(stroke
				(width 0.1)
				(type default)
			)
			(layer "B.Fab")
		)
		(fp_line
			(start 0.12065 -0.305054)
			(end 0.12065 -0.2794)
			(stroke
				(width 0.1)
				(type default)
			)
			(layer "B.Fab")
		)
		(fp_line
			(start 0.12065 -0.2794)
			(end -0.12065 -0.2794)
			(stroke
				(width 0.1)
				(type default)
			)
			(layer "B.Fab")
		)
		(fp_line
			(start 0.12065 0.2794)
			(end 0.12065 0.3048)
			(stroke
				(width 0.1)
				(type default)
			)
			(layer "B.Fab")
		)
		(fp_line
			(start 0.12065 0.3048)
			(end 0.67945 0.3048)
			(stroke
				(width 0.1)
				(type default)
			)
			(layer "B.Fab")
		)
		(fp_line
			(start 0.67945 -0.305054)
			(end 0.12065 -0.305054)
			(stroke
				(width 0.1)
				(type default)
			)
			(layer "B.Fab")
		)
		(fp_line
			(start 0.67945 0.3048)
			(end 0.67945 -0.305054)
			(stroke
				(width 0.1)
				(type default)
			)
			(layer "B.Fab")
		)
		(pad "1" smd circle
			(at 0.40005 0 180)
			(size 0 0)
			(layers "B.Cu" "B.Mask" "B.Paste")
			(net "GND")
		)
		(pad "2" smd circle
			(at -0.40005 0 180)
			(size 0 0)
			(layers "B.Cu" "B.Mask" "B.Paste")
			(net "P1V8_PEX")
		)
	)
)
